(kicad_pcb
	(version 20260206)
	(generator "pcbnew")
	(generator_version "10.0")
	(general
		(thickness 1.6)
		(legacy_teardrops no)
	)
	(paper "A4")
	(title_block
		(title "Bryce Canyon_F.DPB_16315-1-OCP.brd")
		(comment 1 "Bryce Canyon / footprint 407 of 2223 (MONO2), pads 1-74 of 166")
	)
	(layers
		(0 "F.Cu" signal "TOP")
		(4 "In1.Cu" signal "L2GND")
		(6 "In2.Cu" signal "L3")
		(8 "In3.Cu" signal "L4GND")
		(10 "In4.Cu" signal "L5")
		(12 "In5.Cu" signal "L6VCC")
		(14 "In6.Cu" signal "L7VCC")
		(16 "In7.Cu" signal "L8")
		(18 "In8.Cu" signal "L9GND")
		(20 "In9.Cu" signal "L10")
		(22 "In10.Cu" signal "L11GND")
		(2 "B.Cu" signal "BOTTOM")
		(9 "F.Adhes" user "F.Adhesive")
		(11 "B.Adhes" user "B.Adhesive")
		(13 "F.Paste" user "Package Geometry/Pastemask Top")
		(15 "B.Paste" user "Package Geometry/Pastemask Bottom")
		(5 "F.SilkS" user "Ref Des/Silkscreen Top")
		(7 "B.SilkS" user "Ref Des/Silkscreen Bottom")
		(1 "F.Mask" user "Board Geometry/Soldermask Top")
		(3 "B.Mask" user "Board Geometry/Soldermask Bottom")
		(17 "Dwgs.User" user "User.Drawings")
		(19 "Cmts.User" user "User.Comments")
		(21 "Eco1.User" user "User.Eco1")
		(23 "Eco2.User" user "User.Eco2")
		(25 "Edge.Cuts" user "Board Geometry/Outline")
		(27 "Margin" user)
		(31 "F.CrtYd" user "Package Geometry/Place Bound Top")
		(29 "B.CrtYd" user "Package Geometry/Place Bound Bottom")
		(35 "F.Fab" user "Ref Des/Assembly Top")
		(33 "B.Fab" user "Ref Des/Assembly Bottom")
	)
	(footprint ""
		(layer "F.Cu")
		(at 239.300004 -14.85011 90)
		(property "Reference" "MONO2"
			(at 0 0 90)
			(layer "F.SilkS")
			(hide yes)
			(effects
				(font
					(size 1.27 1.27)
				)
			)
		)
		(property "Value" "AMP-CONN164-4R-1-GP"
			(at -25.705054 -1.203706 90)
			(unlocked yes)
			(layer "F.Fab")
			(hide yes)
			(effects
				(font
					(size 1.016 1.016)
					(thickness 0.1524)
				)
			)
		)
		(property "Device Type" "PREFIT-164P-890091-1H441"
			(at -25.705054 -2.727706 90)
			(unlocked yes)
			(layer "F.Fab")
			(hide yes)
			(effects
				(font
					(size 1.016 1.016)
					(thickness 0.1524)
				)
			)
		)
		(duplicate_pad_numbers_are_jumpers no)
		(pad "" np_thru_hole circle
			(at 0 0 90)
			(size 0.254 0.254)
			(drill 2.3622)
			(layers "*.Cu" "*.Mask")
			(clearance 1.4097)
			(thermal_gap 1.4097)
		)
		(pad "" np_thru_hole circle
			(at 73.149968 0 90)
			(size 0.254 0.254)
			(drill 2.3622)
			(layers "*.Cu" "*.Mask")
			(clearance 1.4097)
			(thermal_gap 1.4097)
		)
		(pad "A1" thru_hole circle
			(at -11.649964 -1.249934 90)
			(size 1.0668 1.0668)
			(drill 0.719836)
			(layers "*.Cu" "*.Mask")
			(remove_unused_layers no)
			(net "COMP_A_SEC_INS_N")
			(clearance 0.1905)
			(thermal_gap 0.1905)
		)
		(pad "A2" thru_hole circle
			(at -10.649966 -3.24993 90)
			(size 1.0668 1.0668)
			(drill 0.719836)
			(layers "*.Cu" "*.Mask")
			(remove_unused_layers no)
			(net "P12V_A_COMP")
			(clearance 0.1905)
			(thermal_gap 0.1905)
		)
		(pad "A3" thru_hole circle
			(at -9.649968 -1.249934 90)
			(size 1.0668 1.0668)
			(drill 0.719836)
			(layers "*.Cu" "*.Mask")
			(remove_unused_layers no)
			(net "P12V_A_COMP")
			(clearance 0.1905)
			(thermal_gap 0.1905)
		)
		(pad "A4" thru_hole circle
			(at -8.64997 -3.24993 90)
			(size 1.0668 1.0668)
			(drill 0.719836)
			(layers "*.Cu" "*.Mask")
			(remove_unused_layers no)
			(net "GND")
			(clearance 0.1905)
			(thermal_gap 0.1905)
		)
		(pad "A5" thru_hole circle
			(at -7.649972 -1.249934 90)
			(size 1.0668 1.0668)
			(drill 0.719836)
			(layers "*.Cu" "*.Mask")
			(remove_unused_layers no)
			(net "TP_COMP_A_NCSI_RCLK")
			(clearance 0.1905)
			(thermal_gap 0.1905)
		)
		(pad "A6" thru_hole circle
			(at -6.649974 -3.24993 90)
			(size 1.0668 1.0668)
			(drill 0.719836)
			(layers "*.Cu" "*.Mask")
			(remove_unused_layers no)
			(net "TP_COMP_A_NCSI_RXD0")
			(clearance 0.1905)
			(thermal_gap 0.1905)
		)
		(pad "A7" thru_hole circle
			(at -5.649976 -1.249934 90)
			(size 1.0668 1.0668)
			(drill 0.719836)
			(layers "*.Cu" "*.Mask")
			(remove_unused_layers no)
			(net "TP_COMP_A_NCSI_RXD1")
			(clearance 0.1905)
			(thermal_gap 0.1905)
		)
		(pad "A8" thru_hole circle
			(at -4.649978 -3.24993 90)
			(size 1.0668 1.0668)
			(drill 0.719836)
			(layers "*.Cu" "*.Mask")
			(remove_unused_layers no)
			(net "GND")
			(clearance 0.1905)
			(thermal_gap 0.1905)
		)
		(pad "A9" thru_hole circle
			(at -3.64998 -1.249934 90)
			(size 1.0668 1.0668)
			(drill 0.719836)
			(layers "*.Cu" "*.Mask")
			(remove_unused_layers no)
			(net "PCIE_COMP_A_TO_IOM_A_CLK_4_DP")
			(clearance 0.1905)
			(thermal_gap 0.1905)
		)
		(pad "A10" thru_hole circle
			(at -2.649982 -3.24993 90)
			(size 1.0668 1.0668)
			(drill 0.719836)
			(layers "*.Cu" "*.Mask")
			(remove_unused_layers no)
			(net "PCIE_COMP_A_TO_IOM_A_CLK_4_DN")
			(clearance 0.1905)
			(thermal_gap 0.1905)
		)
		(pad "A11" thru_hole circle
			(at -1.649984 -1.249934 90)
			(size 1.0668 1.0668)
			(drill 0.719836)
			(layers "*.Cu" "*.Mask")
			(remove_unused_layers no)
			(net "GND")
			(clearance 0.1905)
			(thermal_gap 0.1905)
		)
		(pad "A12" thru_hole circle
			(at 1.35001 -3.24993 90)
			(size 1.0668 1.0668)
			(drill 0.719836)
			(layers "*.Cu" "*.Mask")
			(remove_unused_layers no)
			(net "GND")
			(clearance 0.1905)
			(thermal_gap 0.1905)
		)
		(pad "A13" thru_hole circle
			(at 2.350008 -1.249934 90)
			(size 1.0668 1.0668)
			(drill 0.719836)
			(layers "*.Cu" "*.Mask")
			(remove_unused_layers no)
			(net "TP_PCIE_COMP_A_CLK_P5")
			(clearance 0.1905)
			(thermal_gap 0.1905)
		)
		(pad "A14" thru_hole circle
			(at 3.350006 -3.24993 90)
			(size 1.0668 1.0668)
			(drill 0.719836)
			(layers "*.Cu" "*.Mask")
			(remove_unused_layers no)
			(net "TP_PCIE_COMP_A_CLK_N5")
			(clearance 0.1905)
			(thermal_gap 0.1905)
		)
		(pad "A15" thru_hole circle
			(at 4.350004 -1.249934 90)
			(size 1.0668 1.0668)
			(drill 0.719836)
			(layers "*.Cu" "*.Mask")
			(remove_unused_layers no)
			(net "GND")
			(clearance 0.1905)
			(thermal_gap 0.1905)
		)
		(pad "A16" thru_hole circle
			(at 5.350002 -3.24993 90)
			(size 1.0668 1.0668)
			(drill 0.719836)
			(layers "*.Cu" "*.Mask")
			(remove_unused_layers no)
			(net "GND")
			(clearance 0.1905)
			(thermal_gap 0.1905)
		)
		(pad "A17" thru_hole circle
			(at 6.35 -1.249934 90)
			(size 1.0668 1.0668)
			(drill 0.719836)
			(layers "*.Cu" "*.Mask")
			(remove_unused_layers no)
			(net "Net_1399")
			(clearance 0.1905)
			(thermal_gap 0.1905)
		)
		(pad "A18" thru_hole circle
			(at 7.349998 -3.24993 90)
			(size 1.0668 1.0668)
			(drill 0.719836)
			(layers "*.Cu" "*.Mask")
			(remove_unused_layers no)
			(net "Net_1396")
			(clearance 0.1905)
			(thermal_gap 0.1905)
		)
		(pad "A19" thru_hole circle
			(at 8.349996 -1.249934 90)
			(size 1.0668 1.0668)
			(drill 0.719836)
			(layers "*.Cu" "*.Mask")
			(remove_unused_layers no)
			(net "GND")
			(clearance 0.1905)
			(thermal_gap 0.1905)
		)
		(pad "A20" thru_hole circle
			(at 9.349994 -3.24993 90)
			(size 1.0668 1.0668)
			(drill 0.719836)
			(layers "*.Cu" "*.Mask")
			(remove_unused_layers no)
			(net "GND")
			(clearance 0.1905)
			(thermal_gap 0.1905)
		)
		(pad "A21" thru_hole circle
			(at 10.349992 -1.249934 90)
			(size 1.0668 1.0668)
			(drill 0.719836)
			(layers "*.Cu" "*.Mask")
			(remove_unused_layers no)
			(net "Net_1398")
			(clearance 0.1905)
			(thermal_gap 0.1905)
		)
		(pad "A22" thru_hole circle
			(at 11.34999 -3.24993 90)
			(size 1.0668 1.0668)
			(drill 0.719836)
			(layers "*.Cu" "*.Mask")
			(remove_unused_layers no)
			(net "Net_1391")
			(clearance 0.1905)
			(thermal_gap 0.1905)
		)
		(pad "A23" thru_hole circle
			(at 12.349988 -1.249934 90)
			(size 1.0668 1.0668)
			(drill 0.719836)
			(layers "*.Cu" "*.Mask")
			(remove_unused_layers no)
			(net "GND")
			(clearance 0.1905)
			(thermal_gap 0.1905)
		)
		(pad "A24" thru_hole circle
			(at 13.349986 -3.24993 90)
			(size 1.0668 1.0668)
			(drill 0.719836)
			(layers "*.Cu" "*.Mask")
			(remove_unused_layers no)
			(net "GND")
			(clearance 0.1905)
			(thermal_gap 0.1905)
		)
		(pad "A25" thru_hole circle
			(at 14.349984 -1.249934 90)
			(size 1.0668 1.0668)
			(drill 0.719836)
			(layers "*.Cu" "*.Mask")
			(remove_unused_layers no)
			(net "Net_1394")
			(clearance 0.1905)
			(thermal_gap 0.1905)
		)
		(pad "A26" thru_hole circle
			(at 15.349982 -3.24993 90)
			(size 1.0668 1.0668)
			(drill 0.719836)
			(layers "*.Cu" "*.Mask")
			(remove_unused_layers no)
			(net "Net_1390")
			(clearance 0.1905)
			(thermal_gap 0.1905)
		)
		(pad "A27" thru_hole circle
			(at 16.34998 -1.249934 90)
			(size 1.0668 1.0668)
			(drill 0.719836)
			(layers "*.Cu" "*.Mask")
			(remove_unused_layers no)
			(net "GND")
			(clearance 0.1905)
			(thermal_gap 0.1905)
		)
		(pad "A28" thru_hole circle
			(at 17.349978 -3.24993 90)
			(size 1.0668 1.0668)
			(drill 0.719836)
			(layers "*.Cu" "*.Mask")
			(remove_unused_layers no)
			(net "GND")
			(clearance 0.1905)
			(thermal_gap 0.1905)
		)
		(pad "A29" thru_hole circle
			(at 18.349976 -1.249934 90)
			(size 1.0668 1.0668)
			(drill 0.719836)
			(layers "*.Cu" "*.Mask")
			(remove_unused_layers no)
			(net "Net_1388")
			(clearance 0.1905)
			(thermal_gap 0.1905)
		)
		(pad "A30" thru_hole circle
			(at 19.349974 -3.24993 90)
			(size 1.0668 1.0668)
			(drill 0.719836)
			(layers "*.Cu" "*.Mask")
			(remove_unused_layers no)
			(net "Net_1387")
			(clearance 0.1905)
			(thermal_gap 0.1905)
		)
		(pad "A31" thru_hole circle
			(at 20.349972 -1.249934 90)
			(size 1.0668 1.0668)
			(drill 0.719836)
			(layers "*.Cu" "*.Mask")
			(remove_unused_layers no)
			(net "GND")
			(clearance 0.1905)
			(thermal_gap 0.1905)
		)
		(pad "A32" thru_hole circle
			(at 21.34997 -3.24993 90)
			(size 1.0668 1.0668)
			(drill 0.719836)
			(layers "*.Cu" "*.Mask")
			(remove_unused_layers no)
			(net "GND")
			(clearance 0.1905)
			(thermal_gap 0.1905)
		)
		(pad "A33" thru_hole circle
			(at 22.349968 -1.249934 90)
			(size 1.0668 1.0668)
			(drill 0.719836)
			(layers "*.Cu" "*.Mask")
			(remove_unused_layers no)
			(net "PCIE_IOM_A_TO_COMP_A_12_DP")
			(clearance 0.1905)
			(thermal_gap 0.1905)
		)
		(pad "A34" thru_hole circle
			(at 23.349966 -3.24993 90)
			(size 1.0668 1.0668)
			(drill 0.719836)
			(layers "*.Cu" "*.Mask")
			(remove_unused_layers no)
			(net "PCIE_IOM_A_TO_COMP_A_12_DN")
			(clearance 0.1905)
			(thermal_gap 0.1905)
		)
		(pad "A35" thru_hole circle
			(at 24.349964 -1.249934 90)
			(size 1.0668 1.0668)
			(drill 0.719836)
			(layers "*.Cu" "*.Mask")
			(remove_unused_layers no)
			(net "GND")
			(clearance 0.1905)
			(thermal_gap 0.1905)
		)
		(pad "A36" thru_hole circle
			(at 25.349962 -3.24993 90)
			(size 1.0668 1.0668)
			(drill 0.719836)
			(layers "*.Cu" "*.Mask")
			(remove_unused_layers no)
			(net "GND")
			(clearance 0.1905)
			(thermal_gap 0.1905)
		)
		(pad "A37" thru_hole circle
			(at 26.34996 -1.249934 90)
			(size 1.0668 1.0668)
			(drill 0.719836)
			(layers "*.Cu" "*.Mask")
			(remove_unused_layers no)
			(net "PCIE_IOM_A_TO_COMP_A_13_DP")
			(clearance 0.1905)
			(thermal_gap 0.1905)
		)
		(pad "A38" thru_hole circle
			(at 27.349958 -3.24993 90)
			(size 1.0668 1.0668)
			(drill 0.719836)
			(layers "*.Cu" "*.Mask")
			(remove_unused_layers no)
			(net "PCIE_IOM_A_TO_COMP_A_13_DN")
			(clearance 0.1905)
			(thermal_gap 0.1905)
		)
		(pad "A39" thru_hole circle
			(at 28.349956 -1.249934 90)
			(size 1.0668 1.0668)
			(drill 0.719836)
			(layers "*.Cu" "*.Mask")
			(remove_unused_layers no)
			(net "GND")
			(clearance 0.1905)
			(thermal_gap 0.1905)
		)
		(pad "A40" thru_hole circle
			(at 29.349954 -3.24993 90)
			(size 1.0668 1.0668)
			(drill 0.719836)
			(layers "*.Cu" "*.Mask")
			(remove_unused_layers no)
			(net "GND")
			(clearance 0.1905)
			(thermal_gap 0.1905)
		)
		(pad "A41" thru_hole circle
			(at 30.349952 -1.249934 90)
			(size 1.0668 1.0668)
			(drill 0.719836)
			(layers "*.Cu" "*.Mask")
			(remove_unused_layers no)
			(net "PCIE_IOM_A_TO_COMP_A_14_DP")
			(clearance 0.1905)
			(thermal_gap 0.1905)
		)
		(pad "A42" thru_hole circle
			(at 31.34995 -3.24993 90)
			(size 1.0668 1.0668)
			(drill 0.719836)
			(layers "*.Cu" "*.Mask")
			(remove_unused_layers no)
			(net "PCIE_IOM_A_TO_COMP_A_14_DN")
			(clearance 0.1905)
			(thermal_gap 0.1905)
		)
		(pad "A43" thru_hole circle
			(at 32.349948 -1.249934 90)
			(size 1.0668 1.0668)
			(drill 0.719836)
			(layers "*.Cu" "*.Mask")
			(remove_unused_layers no)
			(net "GND")
			(clearance 0.1905)
			(thermal_gap 0.1905)
		)
		(pad "A44" thru_hole circle
			(at 33.349946 -3.24993 90)
			(size 1.0668 1.0668)
			(drill 0.719836)
			(layers "*.Cu" "*.Mask")
			(remove_unused_layers no)
			(net "GND")
			(clearance 0.1905)
			(thermal_gap 0.1905)
		)
		(pad "A45" thru_hole circle
			(at 34.349944 -1.249934 90)
			(size 1.0668 1.0668)
			(drill 0.719836)
			(layers "*.Cu" "*.Mask")
			(remove_unused_layers no)
			(net "PCIE_IOM_A_TO_COMP_A_15_DP")
			(clearance 0.1905)
			(thermal_gap 0.1905)
		)
		(pad "A46" thru_hole circle
			(at 35.349942 -3.24993 90)
			(size 1.0668 1.0668)
			(drill 0.719836)
			(layers "*.Cu" "*.Mask")
			(remove_unused_layers no)
			(net "PCIE_IOM_A_TO_COMP_A_15_DN")
			(clearance 0.1905)
			(thermal_gap 0.1905)
		)
		(pad "A47" thru_hole circle
			(at 36.34994 -1.249934 90)
			(size 1.0668 1.0668)
			(drill 0.719836)
			(layers "*.Cu" "*.Mask")
			(remove_unused_layers no)
			(net "GND")
			(clearance 0.1905)
			(thermal_gap 0.1905)
		)
		(pad "A48" thru_hole circle
			(at 37.349938 -3.24993 90)
			(size 1.0668 1.0668)
			(drill 0.719836)
			(layers "*.Cu" "*.Mask")
			(remove_unused_layers no)
			(net "GND")
			(clearance 0.1905)
			(thermal_gap 0.1905)
		)
		(pad "A49" thru_hole circle
			(at 38.349936 -1.249934 90)
			(size 1.0668 1.0668)
			(drill 0.719836)
			(layers "*.Cu" "*.Mask")
			(remove_unused_layers no)
			(net "PCIE_IOM_A_TO_COMP_A_16_DP")
			(clearance 0.1905)
			(thermal_gap 0.1905)
		)
		(pad "A50" thru_hole circle
			(at 39.349934 -3.24993 90)
			(size 1.0668 1.0668)
			(drill 0.719836)
			(layers "*.Cu" "*.Mask")
			(remove_unused_layers no)
			(net "PCIE_IOM_A_TO_COMP_A_16_DN")
			(clearance 0.1905)
			(thermal_gap 0.1905)
		)
		(pad "A51" thru_hole circle
			(at 40.349932 -1.249934 90)
			(size 1.0668 1.0668)
			(drill 0.719836)
			(layers "*.Cu" "*.Mask")
			(remove_unused_layers no)
			(net "GND")
			(clearance 0.1905)
			(thermal_gap 0.1905)
		)
		(pad "A52" thru_hole circle
			(at 41.34993 -3.24993 90)
			(size 1.0668 1.0668)
			(drill 0.719836)
			(layers "*.Cu" "*.Mask")
			(remove_unused_layers no)
			(net "GND")
			(clearance 0.1905)
			(thermal_gap 0.1905)
		)
		(pad "A53" thru_hole circle
			(at 42.349928 -1.249934 90)
			(size 1.0668 1.0668)
			(drill 0.719836)
			(layers "*.Cu" "*.Mask")
			(remove_unused_layers no)
			(net "PCIE_IOM_A_TO_COMP_A_17_DP")
			(clearance 0.1905)
			(thermal_gap 0.1905)
		)
		(pad "A54" thru_hole circle
			(at 43.349926 -3.24993 90)
			(size 1.0668 1.0668)
			(drill 0.719836)
			(layers "*.Cu" "*.Mask")
			(remove_unused_layers no)
			(net "PCIE_IOM_A_TO_COMP_A_17_DN")
			(clearance 0.1905)
			(thermal_gap 0.1905)
		)
		(pad "A55" thru_hole circle
			(at 44.349924 -1.249934 90)
			(size 1.0668 1.0668)
			(drill 0.719836)
			(layers "*.Cu" "*.Mask")
			(remove_unused_layers no)
			(net "GND")
			(clearance 0.1905)
			(thermal_gap 0.1905)
		)
		(pad "A56" thru_hole circle
			(at 45.349922 -3.24993 90)
			(size 1.0668 1.0668)
			(drill 0.719836)
			(layers "*.Cu" "*.Mask")
			(remove_unused_layers no)
			(net "GND")
			(clearance 0.1905)
			(thermal_gap 0.1905)
		)
		(pad "A57" thru_hole circle
			(at 46.34992 -1.249934 90)
			(size 1.0668 1.0668)
			(drill 0.719836)
			(layers "*.Cu" "*.Mask")
			(remove_unused_layers no)
			(net "PCIE_IOM_A_TO_COMP_A_18_DP")
			(clearance 0.1905)
			(thermal_gap 0.1905)
		)
		(pad "A58" thru_hole circle
			(at 47.349918 -3.24993 90)
			(size 1.0668 1.0668)
			(drill 0.719836)
			(layers "*.Cu" "*.Mask")
			(remove_unused_layers no)
			(net "PCIE_IOM_A_TO_COMP_A_18_DN")
			(clearance 0.1905)
			(thermal_gap 0.1905)
		)
		(pad "A59" thru_hole circle
			(at 48.349916 -1.249934 90)
			(size 1.0668 1.0668)
			(drill 0.719836)
			(layers "*.Cu" "*.Mask")
			(remove_unused_layers no)
			(net "GND")
			(clearance 0.1905)
			(thermal_gap 0.1905)
		)
		(pad "A60" thru_hole circle
			(at 49.349914 -3.24993 90)
			(size 1.0668 1.0668)
			(drill 0.719836)
			(layers "*.Cu" "*.Mask")
			(remove_unused_layers no)
			(net "GND")
			(clearance 0.1905)
			(thermal_gap 0.1905)
		)
		(pad "A61" thru_hole circle
			(at 50.349912 -1.249934 90)
			(size 1.0668 1.0668)
			(drill 0.719836)
			(layers "*.Cu" "*.Mask")
			(remove_unused_layers no)
			(net "PCIE_IOM_A_TO_COMP_A_19_DP")
			(clearance 0.1905)
			(thermal_gap 0.1905)
		)
		(pad "A62" thru_hole circle
			(at 51.34991 -3.24993 90)
			(size 1.0668 1.0668)
			(drill 0.719836)
			(layers "*.Cu" "*.Mask")
			(remove_unused_layers no)
			(net "PCIE_IOM_A_TO_COMP_A_19_DN")
			(clearance 0.1905)
			(thermal_gap 0.1905)
		)
		(pad "A63" thru_hole circle
			(at 52.349908 -1.249934 90)
			(size 1.0668 1.0668)
			(drill 0.719836)
			(layers "*.Cu" "*.Mask")
			(remove_unused_layers no)
			(net "GND")
			(clearance 0.1905)
			(thermal_gap 0.1905)
		)
		(pad "A64" thru_hole circle
			(at 53.349906 -3.24993 90)
			(size 1.0668 1.0668)
			(drill 0.719836)
			(layers "*.Cu" "*.Mask")
			(remove_unused_layers no)
			(net "GND")
			(clearance 0.1905)
			(thermal_gap 0.1905)
		)
		(pad "A65" thru_hole circle
			(at 54.349904 -1.249934 90)
			(size 1.0668 1.0668)
			(drill 0.719836)
			(layers "*.Cu" "*.Mask")
			(remove_unused_layers no)
			(net "PCIE_IOM_A_TO_COMP_A_20_DP")
			(clearance 0.1905)
			(thermal_gap 0.1905)
		)
		(pad "A66" thru_hole circle
			(at 55.349902 -3.24993 90)
			(size 1.0668 1.0668)
			(drill 0.719836)
			(layers "*.Cu" "*.Mask")
			(remove_unused_layers no)
			(net "PCIE_IOM_A_TO_COMP_A_20_DN")
			(clearance 0.1905)
			(thermal_gap 0.1905)
		)
		(pad "A67" thru_hole circle
			(at 56.3499 -1.249934 90)
			(size 1.0668 1.0668)
			(drill 0.719836)
			(layers "*.Cu" "*.Mask")
			(remove_unused_layers no)
			(net "GND")
			(clearance 0.1905)
			(thermal_gap 0.1905)
		)
		(pad "A68" thru_hole circle
			(at 57.349898 -3.24993 90)
			(size 1.0668 1.0668)
			(drill 0.719836)
			(layers "*.Cu" "*.Mask")
			(remove_unused_layers no)
			(net "GND")
			(clearance 0.1905)
			(thermal_gap 0.1905)
		)
		(pad "A69" thru_hole circle
			(at 58.349896 -1.249934 90)
			(size 1.0668 1.0668)
			(drill 0.719836)
			(layers "*.Cu" "*.Mask")
			(remove_unused_layers no)
			(net "PCIE_IOM_A_TO_COMP_A_21_DP")
			(clearance 0.1905)
			(thermal_gap 0.1905)
		)
		(pad "A70" thru_hole circle
			(at 59.349894 -3.24993 90)
			(size 1.0668 1.0668)
			(drill 0.719836)
			(layers "*.Cu" "*.Mask")
			(remove_unused_layers no)
			(net "PCIE_IOM_A_TO_COMP_A_21_DN")
			(clearance 0.1905)
			(thermal_gap 0.1905)
		)
		(pad "A71" thru_hole circle
			(at 60.349892 -1.249934 90)
			(size 1.0668 1.0668)
			(drill 0.719836)
			(layers "*.Cu" "*.Mask")
			(remove_unused_layers no)
			(net "GND")
			(clearance 0.1905)
			(thermal_gap 0.1905)
		)
		(pad "A72" thru_hole circle
			(at 61.34989 -3.24993 90)
			(size 1.0668 1.0668)
			(drill 0.719836)
			(layers "*.Cu" "*.Mask")
			(remove_unused_layers no)
			(net "GND")
			(clearance 0.1905)
			(thermal_gap 0.1905)
		)
	)
)
